# BASEBOARD_FAB2 (Tioga Pass) — schematic parts with pin connectivity, parts 4709–4717 of 4751; source: Cadence DE-HDL packaged netlist (pstxprt.dat, pstxnet.dat, pstchip.dat)

U9F1  FSA3357  IC  pkg SM  page 158
  1  B0  BI  = SP2_BMC_CM_UART_RX_R
  2  B1  BI  = UART_BMC_RXD5
  3  B2  BI  = SP1_BMC_HOST_UART_RX
  4  GND  GROUND  = GND
  5  S2  IN  = FM_UARTSW_MSB_N
  6  S1  IN  = FM_UARTSW_LSB_N
  7  A  BI  = UART_MUX_IN_R
  8  VCC  POWER  = P3V3_STBY

U9F2  FSA3357  IC  pkg SM  page 158
  1  B0  BI  = SP2_BMC_CM_UART_TX_R
  2  B1  BI  = UART_BMC_TXD5
  3  B2  BI  = SP1_BMC_HOST_UART_TX
  4  GND  GROUND  = GND
  5  S2  IN  = FM_UARTSW_MSB_N
  6  S1  IN  = FM_UARTSW_LSB_N
  7  A  BI  = UART_MUX_OUT_R
  8  VCC  POWER  = P3V3_STBY

U9F3  TTL1G07_A  74LVC1G07 IC  pkg SOP  page 151 : 2 = RST_BMC_DDR3_BUF_IN_N ; 4 = RST_BMC_DDR3_R_N

U9G1  GTL2014  IC  pkg SM  page 152
  1  DIR  IN  = PD_DIR_2
  2  B0  BI  = H_CPU1_MEMKLM_MEMHOT_G_R_N
  3  B1  BI  = H_CPU1_MEMGHJ_MEMHOT_G_R_N
  4  VREF  POWER  = P0V7_GTL2014_2
  5  B2  BI  = H_CPU0_MEMDEF_MEMHOT_G_R_N
  6  B3  BI  = H_CPU0_MEMABC_MEMHOT_G_R_N
  7  GND(0)  GROUND  = GND
  8  GND(1)  GROUND  = GND
  9  A3  BI  = H_CPU0_ABC_MEMHOT_LVT3_R_N
  10  A2  BI  = H_CPU0_DEF_MEMHOT_LVT3_R_N
  11  GND(2)  GROUND  = GND
  12  A1  BI  = H_CPU1_GHJ_MEMHOT_LVT3_R_N
  13  A0  BI  = H_CPU1_KLM_MEMHOT_LVT3_R_N
  14  VCC  POWER  = P3V3

U9P1  TPS3700  IC  pkg SM  page 200
  1  OUTB  OUT  = A_P12V_STBY_FPH_GATE
  2  VDD  POWER  = P12V_STBY
  3  INBN  BI  = A_P12V_STBY_FP_TRIGGER
  4  INAP  BI  = A_P12V_STBY_ADR_TRIGGER
  5  GND  GROUND  = GND
  6  OUTA  OUT  = FM_UV_ADR_TRIGGER_N

U9P2  TPS3700  IC  pkg SM  page 200
  1  OUTB  OUT  = FM_HSC_TIMER_EXP_N
  2  VDD  POWER  = P3V3_STBY
  3  INBN  BI  = A_HSC_TIMER_R
  4  INAP  BI  = A_HSC_INAP
  5  GND  GROUND  = GND
  6  OUTA  OUT  = PWRGD_DSW_PWROK

U10W1  TTL1G07_A  74LVC1G07 IC  pkg SOP  page 251 : 2 = PUMP_PWM_OUT ; 4 = PUMP_PWM_OUT_BUF

U14E2  TTL1G08  NC7SZ08 IC  pkg SOTLF  page 248
  1  A(0)  IN  = RST_PCIE_M2_DEV_N
  2  B(0)  IN  = RST_PCIE_M2_DEV_AND
  4  Y(0)  OUT  = RST_PCIE_M2_DEV_IC_N

U14E3  TTL1G08  NC7SZ08 IC  pkg SOTLF  page 248
  1  A(0)  IN  = PWRGD_P12V_HSC_DLY
  2  B(0)  IN  = PWRGD_P3V3
  4  Y(0)  OUT  = RST_PCIE_M2_DEV_AND
